FILE_TYPE = CONNECTIVITY;
{Allegro Design Entry HDL 17.4-2019 S026 (4007227) 1/17/2022}
"PAGE_NUMBER" = 334;
0"NC";
1"P3V3_AUX\g";
2"GND\g";
3"GND\g";
4"GND\g";
5"GND\g";
6"GND\g";
7"P3V3_AUX\g";
8"GND\g";
9"P3V3_AUX\g";
10"GND\g";
11"GND\g";
12"GND\g";
13"GND\g";
14"GND\g";
15"P3V3_AUX\g";
16"GND\g";
17"P3V3_AUX\g";
18"GND\g";
19"P3V3_AUX\g";
20"GND\g";
21"GND\g";
22"GPU_FPGA_BOOT_EN";
23"GPU_FPGA_BOOT_EN_BUF_R";
24"GPU_FPGA_BOOT_EN_BUF";
25"GPU_BASE_STBY_EN";
26"GPU_BASE_STBY_EN_BUF";
27"GPU_BASE_STBY_EN_BUF_R";
28"FM_SWB_PWR_EN_R_BUF";
29"FM_SWB_PWR_EN_R1_BUF";
30"P3V3_AUX\g";
31"P3V3_AUX\g";
32"FM_SWB_PWR_EN_R";
33"RST_PERST_0_SWB_BUF_N";
34"RST_PERST_0_SWB_BUF_R_N";
35"RST_PERST_CPU0_SWB_R_N";
36"RST_PERST_2_SWB_BUF_R_N";
37"RST_PERST_1_SWB_BUF_R_N";
38"P3V3_AUX\g";
39"RST_PERST_1_SWB_BUF_N";
40"RST_PERST_CPU1_SWB_R_N";
41"RST_PERST_2_SWB_BUF_N";
42"RST_PERST_CPU1_SWB_1_R_N";
%"Q_RES"
"2","(-4950,2725)","0","pure_quanta","I123";
;
LOCATION"R3457"
$SEC"1"
CDS_SEC"1"
PACK_TYPE"0402LF"
VALUE"10K"
TOLERANCE"1%"
WATTAGE"1/16W"
MATERIAL"CHIP"
CDS_LIB"pure_quanta"
PART_NUMBER"CS31002FB08";
"A"
$PN"1"27;
"B"
$PN"2"2;
%"Q_RES"
"2","(-4975,3225)","0","pure_quanta","I124";
;
LOCATION"R3456"
$SEC"1"
CDS_SEC"1"
VALUE"100K"
TOLERANCE"1%"
PACK_TYPE"0402LF"
WATTAGE"1/16W"
MATERIAL"EMPTY"
CDS_LIB"pure_quanta"
PART_NUMBER"CS41002FB09";
"A"
$PN"1"1;
"B"
$PN"2"27;
%"UNIVERSAL_POWER"
"1","(-4975,3525)","0","pure_quanta_power","I125";
;
HDL_POWER"P3V3_AUX"
CDS_LIB"pure_quanta_power";
"A"1;
%"UNIVERSAL_GND"
"1","(-4950,2500)","0","pure_quanta_power","I126";
;
CDS_LIB"pure_quanta_power"
HDL_POWER"GND";
"A"2;
%"Q_RES"
"2","(-7600,3350)","0","pure_quanta","I127";
;
LOCATION"R3451"
$SEC"1"
CDS_SEC"1"
PACK_TYPE"0402LF"
TOLERANCE"5%"
WATTAGE"1/16W"
MATERIAL"EMPTY"
VALUE"4.7K"
CDS_LIB"pure_quanta"
PART_NUMBER"CS24702JB10";
"A"
$PN"1"19;
"B"
$PN"2"25;
%"UNIVERSAL_GND"
"1","(-6225,1050)","0","pure_quanta_power","I137";
;
CDS_LIB"pure_quanta_power"
HDL_POWER"GND";
"A"3;
%"UNIVERSAL_GND"
"1","(-4950,750)","0","pure_quanta_power","I138";
;
CDS_LIB"pure_quanta_power"
HDL_POWER"GND";
"A"4;
%"Q_RES"
"2","(-4950,975)","0","pure_quanta","I139";
;
LOCATION"R3455"
$SEC"1"
CDS_SEC"1"
WATTAGE"1/16W"
TOLERANCE"1%"
VALUE"10K"
MATERIAL"CHIP"
PACK_TYPE"0402LF"
CDS_LIB"pure_quanta"
PART_NUMBER"CS31002FB08";
"A"
$PN"1"36;
"B"
$PN"2"4;
%"Q_RES"
"1","(-4625,1250)","0","pure_quanta","I140";
;
LOCATION"R3391"
$SEC"1"
CDS_SEC"1"
PACK_TYPE"0402LF"
MATERIAL"CHIP"
VALUE"49.9"
WATTAGE"1/16W"
TOLERANCE"1%"
CDS_LIB"pure_quanta"
PART_NUMBER"CS04992FB07";
"B"
$PN"2"41;
"A"
$PN"1"36;
%"Q_CAP"
"1","(-6075,2175)","0","pure_quanta","I148";
;
LOCATION"C1957"
$SEC"1"
CDS_SEC"1"
VALUE"0.1UF"
VOLTAGE"25V"
PACK_TYPE"0402"
TOLERANCE"10%"
MATERIAL"X7R"
CDS_LIB"pure_quanta"
PART_NUMBER"CH4104K1B00";
"B"
$PN"2"5;
"A"
$PN"1"30;
%"UNIVERSAL_GND"
"1","(-6075,1950)","0","pure_quanta_power","I149";
;
CDS_LIB"pure_quanta_power"
HDL_POWER"GND";
"A"5;
%"74LVC2G17GW"
"1","(-6250,1575)","0","pure_quanta","I153";
;
LOCATION"U252"
$SEC"1"
CDS_SEC"1"
VALUE"74LVC2G17GW"
MATERIAL"IC"
PART_TYPE"SMLF"
CDS_LIB"pure_quanta"
NEEDS_NO_SIZE"TRUE"
CDS_LMAN_SYM_OUTLINE"-225,275,225,-275"
PART_NUMBER"AL2G0017005";
"B0"
$PN"6"34;
"A1"
$PN"3"42;
"A0"
$PN"1"40;
"GND"
$PN"2"3;
"B1"
$PN"4"36;
"VCC"
$PN"5"30;
%"UNIVERSAL_POWER"
"1","(-6075,2500)","0","pure_quanta_power","I154";
;
HDL_POWER"P3V3_AUX"
CDS_LIB"pure_quanta_power";
"A"30;
%"UNIVERSAL_GND"
"1","(-7575,2625)","0","pure_quanta_power","I16";
;
CDS_LIB"pure_quanta_power"
HDL_POWER"GND";
"A"6;
%"Q_RES"
"1","(-4750,4125)","0","pure_quanta","I162";
;
LOCATION"R3390"
$SEC"1"
CDS_SEC"1"
PACK_TYPE"0402LF"
MATERIAL"CHIP"
VALUE"49.9"
CDS_LIB"pure_quanta"
TOLERANCE"1%"
WATTAGE"1/16W"
PART_NUMBER"CS04992FB07";
"B"
$PN"2"24;
"A"
$PN"1"23;
%"UNIVERSAL_POWER"
"1","(-5000,4675)","0","pure_quanta_power","I163";
;
HDL_POWER"P3V3_AUX"
CDS_LIB"pure_quanta_power";
"A"7;
%"Q_RES"
"2","(-5000,4425)","0","pure_quanta","I164";
;
LOCATION"R3453"
$SEC"1"
CDS_SEC"1"
WATTAGE"1/16W"
TOLERANCE"1%"
VALUE"100K"
PACK_TYPE"0402LF"
MATERIAL"EMPTY"
CDS_LIB"pure_quanta"
PART_NUMBER"CS41002FB09";
"A"
$PN"1"7;
"B"
$PN"2"23;
%"Q_RES"
"2","(-4975,3825)","0","pure_quanta","I165";
;
LOCATION"R3454"
$SEC"1"
CDS_SEC"1"
MATERIAL"CHIP"
TOLERANCE"1%"
VALUE"1K"
WATTAGE"1/16W"
PACK_TYPE"0402LF"
CDS_LIB"pure_quanta"
PART_NUMBER"CS21002FB06";
"A"
$PN"1"23;
"B"
$PN"2"8;
%"UNIVERSAL_GND"
"1","(-4975,3625)","0","pure_quanta_power","I166";
;
CDS_LIB"pure_quanta_power"
HDL_POWER"GND";
"A"8;
%"UNIVERSAL_POWER"
"1","(-7600,4650)","0","pure_quanta_power","I167";
;
HDL_POWER"P3V3_AUX"
CDS_LIB"pure_quanta_power";
"A"9;
%"Q_RES"
"2","(-7600,4400)","0","pure_quanta","I168";
;
LOCATION"R3448"
$SEC"1"
CDS_SEC"1"
VALUE"4.7K"
MATERIAL"EMPTY"
PACK_TYPE"0402LF"
WATTAGE"1/16W"
TOLERANCE"5%"
CDS_LIB"pure_quanta"
PART_NUMBER"CS24702JB10";
"A"
$PN"1"9;
"B"
$PN"2"22;
%"Q_RES"
"2","(-7575,3925)","0","pure_quanta","I170";
;
LOCATION"R3449"
$SEC"1"
CDS_SEC"1"
WATTAGE"1/16W"
PACK_TYPE"0402LF"
TOLERANCE"1%"
MATERIAL"CHIP"
VALUE"100K"
CDS_LIB"pure_quanta"
PART_NUMBER"CS41002FB09";
"A"
$PN"1"22;
"B"
$PN"2"10;
%"UNIVERSAL_GND"
"1","(-7575,3725)","0","pure_quanta_power","I171";
;
CDS_LIB"pure_quanta_power"
HDL_POWER"GND";
"A"10;
%"74LVC2G17GW"
"1","(-6325,-275)","0","pure_quanta","I173";
;
LOCATION"U256"
$SEC"1"
CDS_SEC"1"
MATERIAL"IC"
PART_TYPE"SMLF"
VALUE"74LVC2G17GW"
CDS_LIB"pure_quanta"
NEEDS_NO_SIZE"TRUE"
CDS_LMAN_SYM_OUTLINE"-225,275,225,-275"
PART_NUMBER"AL2G0017005";
"B0"
$PN"6"37;
"A1"
$PN"3"32;
"A0"
$PN"1"35;
"GND"
$PN"2"12;
"B1"
$PN"4"29;
"VCC"
$PN"5"38;
%"UNIVERSAL_POWER"
"1","(-6175,625)","0","pure_quanta_power","I174";
;
HDL_POWER"P3V3_AUX"
CDS_LIB"pure_quanta_power";
"A"38;
%"Q_CAP"
"1","(-6175,300)","0","pure_quanta","I175";
;
LOCATION"C1977"
$SEC"1"
CDS_SEC"1"
TOLERANCE"10%"
PACK_TYPE"0402"
VALUE"0.1UF"
VOLTAGE"25V"
MATERIAL"X7R"
CDS_LIB"pure_quanta"
PART_NUMBER"CH4104K1B00";
"B"
$PN"2"11;
"A"
$PN"1"38;
%"UNIVERSAL_GND"
"1","(-6175,75)","0","pure_quanta_power","I176";
;
CDS_LIB"pure_quanta_power"
HDL_POWER"GND";
"A"11;
%"UNIVERSAL_GND"
"1","(-6300,-850)","0","pure_quanta_power","I177";
;
CDS_LIB"pure_quanta_power"
HDL_POWER"GND";
"A"12;
%"UNIVERSAL_GND"
"1","(-4950,1400)","0","pure_quanta_power","I178";
;
CDS_LIB"pure_quanta_power"
HDL_POWER"GND";
"A"13;
%"Q_RES"
"1","(-4625,1900)","0","pure_quanta","I180";
;
LOCATION"R3469"
$SEC"1"
CDS_SEC"1"
MATERIAL"CHIP"
PACK_TYPE"0402LF"
VALUE"49.9"
CDS_LIB"pure_quanta"
TOLERANCE"1%"
WATTAGE"1/16W"
PART_NUMBER"CS04992FB07";
"B"
$PN"2"33;
"A"
$PN"1"34;
%"Q_RES"
"2","(-4950,1625)","0","pure_quanta","I181";
;
LOCATION"R3467"
$SEC"1"
CDS_SEC"1"
MATERIAL"CHIP"
VALUE"10K"
TOLERANCE"1%"
WATTAGE"1/16W"
PACK_TYPE"0402LF"
CDS_LIB"pure_quanta"
PART_NUMBER"CS31002FB08";
"A"
$PN"1"34;
"B"
$PN"2"13;
%"Q_RES"
"1","(-4650,100)","0","pure_quanta","I183";
;
LOCATION"R3468"
$SEC"1"
CDS_SEC"1"
VALUE"49.9"
MATERIAL"CHIP"
PACK_TYPE"0402LF"
WATTAGE"1/16W"
TOLERANCE"1%"
CDS_LIB"pure_quanta"
PART_NUMBER"CS04992FB07";
"B"
$PN"2"39;
"A"
$PN"1"37;
%"Q_RES"
"2","(-4975,-175)","0","pure_quanta","I184";
;
LOCATION"R3466"
$SEC"1"
CDS_SEC"1"
TOLERANCE"1%"
WATTAGE"1/16W"
MATERIAL"CHIP"
PACK_TYPE"0402LF"
VALUE"10K"
CDS_LIB"pure_quanta"
PART_NUMBER"CS31002FB08";
"A"
$PN"1"37;
"B"
$PN"2"14;
%"UNIVERSAL_GND"
"1","(-4975,-400)","0","pure_quanta_power","I185";
;
CDS_LIB"pure_quanta_power"
HDL_POWER"GND";
"A"14;
%"UNIVERSAL_POWER"
"1","(-7800,125)","0","pure_quanta_power","I186";
;
HDL_POWER"P3V3_AUX"
CDS_LIB"pure_quanta_power";
"A"15;
%"Q_RES"
"2","(-7800,-125)","0","pure_quanta","I187";
;
LOCATION"R2910"
$SEC"1"
CDS_SEC"1"
TOLERANCE"1%"
WATTAGE"1/16W"
MATERIAL"EMPTY"
VALUE"100K"
PACK_TYPE"0402LF"
CDS_LIB"pure_quanta"
PART_NUMBER"CS41002FB09";
"A"
$PN"1"15;
"B"
$PN"2"32;
%"Q_RES"
"2","(-7775,-600)","0","pure_quanta","I188";
;
LOCATION"R2918"
$SEC"1"
CDS_SEC"1"
PACK_TYPE"0402LF"
TOLERANCE"5%"
MATERIAL"CHIP"
VALUE"4.7K"
WATTAGE"1/16W"
CDS_LIB"pure_quanta"
PART_NUMBER"CS24702JB10";
"A"
$PN"1"32;
"B"
$PN"2"16;
%"UNIVERSAL_GND"
"1","(-7775,-775)","0","pure_quanta_power","I189";
;
CDS_LIB"pure_quanta_power"
HDL_POWER"GND";
"A"16;
%"UNIVERSAL_POWER"
"1","(-4150,-50)","0","pure_quanta_power","I191";
;
HDL_POWER"P3V3_AUX"
CDS_LIB"pure_quanta_power";
"A"17;
%"Q_RES"
"2","(-4150,-300)","0","pure_quanta","I192";
;
LOCATION"R2914"
$SEC"1"
CDS_SEC"1"
TOLERANCE"5%"
MATERIAL"EMPTY"
PACK_TYPE"0402LF"
VALUE"4.7K"
WATTAGE"1/16W"
CDS_LIB"pure_quanta"
PART_NUMBER"CS24702JB10";
"A"
$PN"1"17;
"B"
$PN"2"29;
%"Q_RES"
"1","(-3925,-525)","0","pure_quanta","I193";
;
LOCATION"R3515"
$SEC"1"
CDS_SEC"1"
MATERIAL"CHIP"
PACK_TYPE"0402LF"
VALUE"49.9"
TOLERANCE"1%"
WATTAGE"1/16W"
CDS_LIB"pure_quanta"
PART_NUMBER"CS04992FB07";
"B"
$PN"2"28;
"A"
$PN"1"29;
%"Q_RES"
"2","(-4125,-800)","0","pure_quanta","I195";
;
LOCATION"R2932"
$SEC"1"
CDS_SEC"1"
PACK_TYPE"0402LF"
WATTAGE"1/16W"
MATERIAL"CHIP"
TOLERANCE"5%"
VALUE"4.7K"
CDS_LIB"pure_quanta"
PART_NUMBER"CS24702JB10";
"A"
$PN"1"29;
"B"
$PN"2"18;
%"UNIVERSAL_GND"
"1","(-4125,-1025)","0","pure_quanta_power","I196";
;
CDS_LIB"pure_quanta_power"
HDL_POWER"GND";
"A"18;
%"UNIVERSAL_POWER"
"1","(-7600,3525)","0","pure_quanta_power","I20";
;
HDL_POWER"P3V3_AUX"
CDS_LIB"pure_quanta_power";
"A"19;
%"74LVC2G17GW"
"1","(-6125,3575)","0","pure_quanta","I26";
;
LOCATION"U253"
$SEC"1"
CDS_SEC"1"
VALUE"74LVC2G17GW"
PART_TYPE"SMLF"
MATERIAL"IC"
CDS_LIB"pure_quanta"
NEEDS_NO_SIZE"TRUE"
CDS_LMAN_SYM_OUTLINE"-225,275,225,-275"
PART_NUMBER"AL2G0017005";
"B0"
$PN"6"23;
"A1"
$PN"3"25;
"A0"
$PN"1"22;
"GND"
$PN"2"20;
"B1"
$PN"4"27;
"VCC"
$PN"5"31;
%"UNIVERSAL_GND"
"1","(-6100,2975)","0","pure_quanta_power","I27";
;
CDS_LIB"pure_quanta_power"
HDL_POWER"GND";
"A"20;
%"UNIVERSAL_GND"
"1","(-5975,4275)","0","pure_quanta_power","I28";
;
CDS_LIB"pure_quanta_power"
HDL_POWER"GND";
"A"21;
%"Q_CAP"
"1","(-5975,4500)","0","pure_quanta","I29";
;
LOCATION"C1958"
$SEC"1"
CDS_SEC"1"
TOLERANCE"10%"
MATERIAL"X7R"
PACK_TYPE"0402"
VOLTAGE"25V"
VALUE"0.1UF"
CDS_LIB"pure_quanta"
PART_NUMBER"CH4104K1B00";
"B"
$PN"2"21;
"A"
$PN"1"31;
%"UNIVERSAL_POWER"
"1","(-5975,4825)","0","pure_quanta_power","I30";
;
HDL_POWER"P3V3_AUX"
CDS_LIB"pure_quanta_power";
"A"31;
%"Q_RES"
"1","(-4625,3000)","0","pure_quanta","I62";
;
LOCATION"R3392"
$SEC"1"
CDS_SEC"1"
MATERIAL"CHIP"
PACK_TYPE"0402LF"
VALUE"49.9"
WATTAGE"1/16W"
TOLERANCE"1%"
CDS_LIB"pure_quanta"
PART_NUMBER"CS04992FB07";
"B"
$PN"2"26;
"A"
$PN"1"27;
%"Q_RES"
"2","(-7575,2875)","0","pure_quanta","I95";
;
LOCATION"R3452"
$SEC"1"
CDS_SEC"1"
WATTAGE"1/16W"
VALUE"100K"
PACK_TYPE"0402LF"
MATERIAL"CHIP"
TOLERANCE"1%"
CDS_LIB"pure_quanta"
PART_NUMBER"CS41002FB09";
"A"
$PN"1"25;
"B"
$PN"2"6;
END.
